# S9S_MB_2U (Grand Teton) — schematic parts with pin connectivity, parts 5972–5982 of 6093; source: Cadence DE-HDL packaged netlist (pstxprt.dat, pstxnet.dat, pstchip.dat)

U237  PI3EQX12902AZLEX  IC  pkg TQFN30_TH_0-4_4-5X2-5  page 166
  1  VDD1  POWER  = P3V3_AUX
  2  AIP  IN  = P2E_MB_BMC_TX_C_R1_DP<0>
  3  AIN  IN  = P2E_MB_BMC_TX_C_R1_DN<0>
  4  GND1  POWER  = GND
  5  \test#\  IN  = PU_TEST
  6  GND2  POWER  = GND
  7  GND3  POWER  = GND
  8  BON  OUT  = P2E_MB_BMC_RX_BUF_C_DN<0>
  9  BOP  OUT  = P2E_MB_BMC_RX_BUF_C_DP<0>
  10  VDD2  POWER  = P3V3_AUX
  11  \en#\  IN  = FM_P2E_EN_N
  12  SWB  IN  = FM_P2E_SWB
  13  GND4  POWER  = GND
  14  FGB  IN  = FM_P2E_FGB
  15  EQB1  IN  = FM_P2E_EQB1
  16  VDD3  POWER  = P3V3_AUX
  17  BIP  IN  = P2E_MB_BMC_RX_R1_DP<0>
  18  BIN  IN  = P2E_MB_BMC_RX_R1_DN<0>
  19  GND5  POWER  = GND
  20  EQB0  IN  = FM_P2E_EQB0
  21  EQA0  IN  = FM_P2E_EQA0
  22  GND6  POWER  = GND
  23  AON  OUT  = P2E_MB_BMC_TX_BUF_DN<0>
  24  AOP  OUT  = P2E_MB_BMC_TX_BUF_DP<0>
  25  VDD4  POWER  = P3V3_AUX
  26  EQA1  IN  = FM_P2E_EQA1
  27  FGA  IN  = FM_P2E_FGA
  28  GND7  POWER  = GND
  29  SWA  IN  = FM_P2E_SWA
  30  MODE  IN  = FM_P2E_MODE
  TH  GND_TH  POWER  = GND

U239  74LVC1G126SE7  74LVC1G126SE-7 IC  pkg SOT353_0-65_2X1-25  page 190
  1  OE  IN  = PU_BUFFER_HDD_ACTIVITY
  2  A  IN  = LED_HDD_ACTIVITY_N
  3  GND  POWER  = GND
  4  Y  OUT  = LED_HDD_ACTIVITY_B_N
  5  VCC  POWER  = P3V3_AUX

U240  74LVC2G08DP  IC  pkg TSSOP8_0-65_3X3  page 165
  1  \1a\  IN  = OCP_SFF_PRSNT0_R_N
  2  \1b\  IN  = OCP_SFF_PRSNT1_R_N
  3  \2y\  OUT  = OCP_SFF_PRSNT23_R_N
  4  GND  POWER  = GND
  5  \2a\  IN  = OCP_SFF_PRSNT2_R_N
  6  \2b\  IN  = OCP_SFF_PRSNT3_R_N
  7  \1y\  OUT  = OCP_SFF_PRSNT01_R_N
  8  VCC  POWER  = P3V3_AUX

U241  74LVC2G08DP  IC  pkg TSSOP8_0-65_3X3  page 165
  1  \1a\  IN  = OCP_V3_2_PRSNT0_R_N
  2  \1b\  IN  = OCP_V3_2_PRSNT1_R_N
  3  \2y\  OUT  = OCP_V3_2_PRSNT23_R_N
  4  GND  POWER  = GND
  5  \2a\  IN  = OCP_V3_2_PRSNT2_R_N
  6  \2b\  IN  = OCP_V3_2_PRSNT3_R_N
  7  \1y\  OUT  = OCP_V3_2_PRSNT01_R_N
  8  VCC  POWER  = P3V3_AUX

U242  74LVC2G08DP  IC  pkg TSSOP8_0-65_3X3  page 165
  1  \1a\  IN  = OCP_SFF_PRSNT01_R_N
  2  \1b\  IN  = OCP_SFF_PRSNT23_R_N
  3  \2y\  OUT  = OCP_V3_2_PRSNT_ALL_R_N
  4  GND  POWER  = GND
  5  \2a\  IN  = OCP_V3_2_PRSNT01_R_N
  6  \2b\  IN  = OCP_V3_2_PRSNT23_R_N
  7  \1y\  OUT  = OCP_SFF_PRSNT_ALL_R_N
  8  VCC  POWER  = P3V3_AUX

U243  NC7SB3157  NC7SB3157P6X EMPTY  pkg SMLF  page 165
  1  B1  BI  = OCP_SFF_NOT_PRSNT_RBT_ARB_IN
  2  GND  POWER  = GND
  3  B0  BI  = OCP_SFF_RBT_ARB_OUT
  4  A  BI  = OCP_SFF_RBT_ARB_IN_MUX2
  5  VCC  POWER  = P3V3_AUX
  6  S  IN  = OCP_SFF_PRSNT_ALL_R1_N

U244  NC7SB3157  NC7SB3157P6X EMPTY  pkg SMLF  page 165
  1  B1  BI  = OCP_SFF_NOT_PRSNT_RBT_ARB_IN
  2  GND  POWER  = GND
  3  B0  BI  = OCP_SFF_RBT_ARB_IN
  4  A  BI  = OCP_SFF_RBT_ARB_IN_MUX1_R
  5  VCC  POWER  = P3V3_AUX
  6  S  IN  = OCP_SFF_PRSNT_ALL_R3_N

U245  NC7SB3157  NC7SB3157P6X EMPTY  pkg SMLF  page 165
  1  B1  BI  = OCP_V3_2_NOT_PRSNT_RBT_ARB_IN
  2  GND  POWER  = GND
  3  B0  BI  = OCP_V3_2_RBT_ARB_IN
  4  A  BI  = OCP_SFF_RBT_ARB_IN_MUX2_R
  5  VCC  POWER  = P3V3_AUX
  6  S  IN  = OCP_V3_2_PRSNT_ALL_R3_N

U246  NC7SB3157  NC7SB3157P6X EMPTY  pkg SMLF  page 165
  1  B1  BI  = OCP_V3_2_NOT_PRSNT_RBT_ARB_IN
  2  GND  POWER  = GND
  3  B0  BI  = OCP_V3_2_RBT_ARB_OUT
  4  A  BI  = OCP_SFF_RBT_ARB_IN_MUX1
  5  VCC  POWER  = P3V3_AUX
  6  S  IN  = OCP_V3_2_PRSNT_ALL_R1_N

U247  9FGL0251DKILFT  IC  pkg VFQFPN24_TH_0-5_4X4XI  page 212
  1  \xin||clkin_25\  IN  = CLK_GEN2_XTAL_IN
  2  X2  OUT  = CLK_GEN2_XTAL_OUT
  3  \vddxtal3.3\  POWER  = VFG3P3_CLK_GEN
  4  \vsadr||ref3.3\  BI  = CLK_GEN2_SMB_SADR
  5  GNDREF  POWER  = GND
  6  GNDDIG  POWER  = GND
  7  \vdddig3.3\  POWER  = VFG3P3_CLK_GEN
  8  \sclk_3.3\  IN  = SMB_HOST_CLK_GEN2_3V3AUX_SCL
  9  \sdata_3.3\  BI  = SMB_HOST_CLK_GEN2_3V3AUX_SDA
  10  GND_10  POWER  = GND
  11  \vdd3.3_11\  POWER  = VFG3P3_CLK_GEN
  12  \voe0#\  IN  = CLK_GEN2_BMC_RC_OE_R3_N
  13  DIF0  OUT  = CLK_100M_BMC_RC_DP_R
  14  \dif0#\  OUT  = CLK_100M_BMC_RC_DN_R
  15  GNDA  POWER  = GND
  16  \vdda3.3\  POWER  = VFG_3P3A_CLK_GEN
  17  DIF1  OUT  = CLK_100M_GPU_FPGA_DP_R
  18  \dif1#\  OUT  = CLK_100M_GPU_FPGA_DN_R
  19  \voe1#\  IN  = CLK_GEN2_GPU_OE_N
  20  \vdd3.3_20\  POWER  = VFG3P3_CLK_GEN
  21  GND_21  POWER  = GND
  22  \^ckpwrgd_pd#\  IN  = P3V3_PWRGD_CLKGEN
  23  \^vss_en_tri\  IN  = FG_SS_EN
  24  GNDXTAL  POWER  = GND
  25  TH_GND  POWER  = GND

U248  74LVC1G32GW  IC  pkg SMLF  page 212
  1  I0  IN  = GPU_FPGA_READY_R_N
  2  I1  IN  = CLK_GEN2_GPU_FPGA_OE_R2_N
  3  GND  POWER  = GND
  4  O  OUT  = CLK_GEN2_GPU_FPGA_OE_OR_N
  5  VCC  POWER  = P3V3_AUX
